FILE_TYPE = CONNECTIVITY;
{Allegro Design Entry HDL 16.6-p007 (v16-6-112F) 10/10/2012}
"PAGE_NUMBER" = 133;
0"NC";
1"GND\g";
2"P3V3_STBY\g";
3"P3V3_STBY\g";
4"P3V3_STBY\g";
5"P3V3_STBY\g";
6"P3V3_STBY\g";
7"P3V3_STBY\g";
8"P3V3_STBY\g";
9"P3V3_STBY\g";
10"P1V05_PCH_STBY\g";
11"P3V3_STBY\g";
12"P3V3_STBY\g";
13"FM_WBG_PRSNT_N";
14"FM_SINT_PRSNT_N";
15"FM_PCH_PRSNT_N";
16"FM_PRSNT_2_1_N";
17"FM_PRSNT_2_2_N";
18"FM_PRSNT_2_3_N";
19"FM_PRSNT_2_4_N";
20"FM_PRSNT_2_5_N";
21"FM_PRSNT_2_6_N";
22"FM_CPU0_RC_ERROR_N";
23"FM_CPU1_RC_ERROR_N";
24"FM_OCP_MEZZB_PRES_N";
25"FM_OCP_MEZZC_PRES_N";
26"FM_PCH_PLD_DATA";
27"FM_XRC_PRESENT_N";
28"FM_XRC_READY_N";
29"IRQ_HSC_FAULT_N";
30"IRQ_PCH_NIC_ALERT_N";
31"FM_BIOS_SMI_ACTIVE_N";
32"FM_CPU0_RC_EN";
33"FP_PWR_ID_LED_N";
34"IRQ_BOARD_BMC_ALERT_N";
35"PU_10GBE_LOM_PCI_DISABLE_N";
36"PWRGD_SYS_PWROK";
37"PWRGD_PCH_PWROK";
38"FM_TPM_PRES_N";
39"PU_LPC_PME_N";
40"PU_IRQ_PCH_SCI_WHEA_N";
41"FM_OCP_MEZZA_PRES_N";
42"FM_SLT_CFG1";
43"IRQ_BMC_PCH_SMI_LPC_N";
44"FM_SLT_CFG0";
45"FM_CPU1_RC_EN";
46"FM_THROTTLE_N";
47"IRQ_BMC_PCH_SCI_LPC_N";
48"PU_FM_RCIN_N";
49"IRQ_PIRQA_SPI_TPM_N";
50"FM_BMC_READY_N";
51"IRQ_LPC_SERIRQ_N";
52"PU_IRQ_VRALERT_N";
53"FM_BIOS_POST_CMPLT_N";
54"PU_LPC_CLKRUN_N";
%"GND"
"1","(-2825,3600)","0","mstr_symbols","I110";
;
VOLTAGE"0"
HDL_POWER"GND"
BOM_COST"SB"
CDS_LIB"mstr_symbols"
SIZE"1B"
BODY_TYPE"PLUMBING";
"A\NAC"1;
%"RES"
"1","(-2500,3850)","0","mstr_discrete","I120";
;
CDS_SEC"1"
$SEC"1"
CDS_LIB"mstr_discrete"
ROOM"SB"
BOM_COST"SB"
CDS_LOCATION"R3N3"
PACK_TYPE"0402"
PART_NUMBER"G21796-001"
TOLERANCE"1%"
MATERIAL"CHIP"
VALUE"2.0K"
LOCATION"R3N3"
WATTAGE"1/16W";
"B"
$PN"2"37;
"A"
$PN"1"1;
%"RES"
"1","(-2500,4075)","0","mstr_discrete","I122";
;
$SEC"1"
CDS_SEC"1"
CDS_LOCATION"R2N12"
CDS_LIB"mstr_discrete"
ROOM"SB"
BOM_COST"SB"
PART_NUMBER"G21796-016"
LOCATION"R2N12"
PACK_TYPE"0402"
TOLERANCE"1%"
VALUE"10.0K"
MATERIAL"EMPTY"
WATTAGE"1/16W";
"B"
$PN"2"36;
"A"
$PN"1"1;
%"RES"
"1","(-4700,4500)","0","mstr_discrete","I200";
;
CDS_SEC"1"
SEC"1"
SEC_TYPE"0402"
ROOM"SB"
CDS_LIB"mstr_discrete"
CDS_LOCATION"R7D8"
PART_NUMBER"G21796-016"
PACK_TYPE"0402"
MATERIAL"CHIP"
WATTAGE"1/16W"
TOLERANCE"1%"
LOCATION"R7D8"
VALUE"10.0K";
"B"
$PN"2"54;
"A"
$PN"1"8;
%"RES"
"1","(-4700,4325)","0","mstr_discrete","I202";
;
CDS_SEC"1"
ROOM"SB"
SEC_TYPE"0402"
SEC"1"
CDS_LOCATION"R7D10"
CDS_LIB"mstr_discrete"
PART_NUMBER"G21796-016"
PACK_TYPE"0402"
MATERIAL"CHIP"
LOCATION"R7D10"
WATTAGE"1/16W"
TOLERANCE"1%"
VALUE"10.0K";
"B"
$PN"2"39;
"A"
$PN"1"8;
%"RES"
"1","(-4700,3925)","0","mstr_discrete","I237";
;
CDS_SEC"1"
SEC"1"
SEC_TYPE"0402"
ROOM"SB"
CDS_LIB"mstr_discrete"
CDS_LOCATION"R7D12"
PART_NUMBER"G21796-016"
MATERIAL"CHIP"
PACK_TYPE"0402"
LOCATION"R7D12"
WATTAGE"1/16W"
TOLERANCE"1%"
VALUE"10.0K";
"B"
$PN"2"41;
"A"
$PN"1"8;
%"RES"
"1","(-4700,4900)","0","mstr_discrete","I243";
;
CDS_SEC"1"
SEC"1"
SEC_TYPE"0402"
CDS_LIB"mstr_discrete"
CDS_LOCATION"R7D3"
ROOM"SB"
PACK_TYPE"0402"
MATERIAL"CHIP"
PART_NUMBER"G21796-072"
LOCATION"R7D3"
TOLERANCE"1%"
VALUE"4.75K"
WATTAGE"1/16W";
"B"
$PN"2"51;
"A"
$PN"1"8;
%"RES"
"1","(-4700,4125)","0","mstr_discrete","I245";
;
CDS_SEC"1"
SEC"1"
SEC_TYPE"0402"
CDS_LIB"mstr_discrete"
CDS_LOCATION"R7D4"
ROOM"SB"
PART_NUMBER"G21796-016"
LOCATION"R7D4"
MATERIAL"CHIP"
PACK_TYPE"0402"
WATTAGE"1/16W"
TOLERANCE"1%"
VALUE"10.0K";
"B"
$PN"2"40;
"A"
$PN"1"8;
%"RES"
"1","(-4650,2725)","0","mstr_discrete","I247";
;
$SEC"1"
CDS_SEC"1"
BOM_COST"SB"
CDS_LIB"mstr_discrete"
ROOM"SB"
CDS_LOCATION"R2N16"
PACK_TYPE"0402"
PART_NUMBER"G21796-016"
MATERIAL"CHIP"
TOLERANCE"1%"
LOCATION"R2N16"
VALUE"10.0K"
WATTAGE"1/16W";
"B"
$PN"2"52;
"A"
$PN"1"2;
%"P3V3_STBY"
"1","(-4950,2925)","0","mstr_symbols","I251";
;
VOLTAGE"3.3V"
CDS_LIB"mstr_symbols"
SIZE"1B"
BODY_TYPE"PLUMBING"
HDL_POWER"P3V3_STBY";
"G\NAC"2;
%"P3V3_STBY"
"1","(-5075,1975)","0","mstr_symbols","I256";
;
SIZE"1B"
CDS_LIB"mstr_symbols"
BODY_TYPE"PLUMBING"
VOLTAGE"3.3V"
HDL_POWER"P3V3_STBY";
"G\NAC"3;
%"RES"
"1","(-2600,5125)","0","mstr_discrete","I258";
;
CDS_SEC"1"
SEC"1"
SEC_TYPE"0402"
CDS_LIB"mstr_discrete"
ROOM"SB"
CDS_LOCATION"R2R5"
BOM_COST"SB"
PART_NUMBER"G21796-026"
LOCATION"R2R5"
WATTAGE"1/16W"
MATERIAL"CHIP"
PACK_TYPE"0402"
TOLERANCE"1%"
VALUE"1.00K";
"B"
$PN"2"26;
"A"
$PN"1"4;
%"P3V3_STBY"
"1","(-2825,5350)","0","mstr_symbols","I260";
;
SIZE"1B"
CDS_LIB"mstr_symbols"
VOLTAGE"3.3V"
BODY_TYPE"PLUMBING"
HDL_POWER"P3V3_STBY";
"G\NAC"4;
%"RES"
"1","(-2475,1275)","0","mstr_discrete","I267";
;
CDS_SEC"1"
ROOM"SB"
CDS_LOCATION"R2N9"
SEC"1"
SEC_TYPE"0402"
CDS_LIB"mstr_discrete"
PACK_TYPE"0402"
PART_NUMBER"G21796-016"
LOCATION"R2N9"
MATERIAL"CHIP"
TOLERANCE"1%"
VALUE"10.0K"
WATTAGE"1/16W";
"B"
$PN"2"35;
"A"
$PN"1"5;
%"P3V3_STBY"
"1","(-2750,1425)","0","mstr_symbols","I268";
;
SIZE"1B"
CDS_LIB"mstr_symbols"
BODY_TYPE"PLUMBING"
VOLTAGE"3.3V"
HDL_POWER"P3V3_STBY";
"G\NAC"5;
%"RES"
"1","(-2575,4675)","0","mstr_discrete","I280";
;
CDS_SEC"1"
SEC_TYPE"0402"
SEC"1"
ROOM"SB"
CDS_LIB"mstr_discrete"
CDS_LOCATION"R8B23"
BOM_COST"SB"
WATTAGE"1/16W"
PART_NUMBER"G21796-026"
MATERIAL"CHIP"
TOLERANCE"1%"
PACK_TYPE"0402"
LOCATION"R8B23"
VALUE"1.00K";
"B"
$PN"2"27;
"A"
$PN"1"4;
%"RES"
"1","(-2575,4425)","0","mstr_discrete","I282";
;
CDS_SEC"1"
SEC_TYPE"0402"
SEC"1"
CDS_LOCATION"R8B30"
ROOM"SB"
CDS_LIB"mstr_discrete"
BOM_COST"SB"
WATTAGE"1/16W"
MATERIAL"CHIP"
PART_NUMBER"G21796-026"
PACK_TYPE"0402"
TOLERANCE"1%"
LOCATION"R8B30"
VALUE"1.00K";
"B"
$PN"2"28;
"A"
$PN"1"4;
%"RES"
"1","(-2600,4900)","0","mstr_discrete","I284";
;
CDS_SEC"1"
SEC"1"
SEC_TYPE"0402"
ROOM"SB"
CDS_LIB"mstr_discrete"
BOM_COST"SB"
CDS_LOCATION"R2M4"
WATTAGE"1/16W"
PART_NUMBER"G21796-026"
MATERIAL"CHIP"
PACK_TYPE"0402"
TOLERANCE"1%"
VALUE"1.00K"
LOCATION"R2M4";
"B"
$PN"2"29;
"A"
$PN"1"4;
%"RES"
"1","(-4800,950)","0","mstr_discrete","I286";
;
CDS_SEC"1"
SEC_TYPE"0402"
SEC"1"
CDS_LOCATION"R8C4"
BOM_COST"SB_PU_PD"
ROOM"SB"
CDS_LIB"mstr_discrete"
LOCATION"R8C4"
MATERIAL"CHIP"
PACK_TYPE"0402"
TOLERANCE"1%"
PART_NUMBER"G21796-026"
WATTAGE"1/16W"
VALUE"1.00K";
"B"
$PN"2"43;
"A"
$PN"1"3;
%"RES"
"2","(-175,1425)","0","mstr_discrete","I295";
;
CDS_SEC"1"
ROOM"SB_PU_PD"
SEC_TYPE"0402"
SEC"1"
CDS_LOCATION"R7B6"
CDS_LIB"mstr_discrete"
VALUE"10.0K"
PART_NUMBER"G21796-016"
WATTAGE"1/16W"
LOCATION"R7B6"
MATERIAL"CHIP"
TOLERANCE"1%"
PACK_TYPE"0402";
"A"
$PN"1"6;
"B"
$PN"2"15;
%"RES"
"2","(-425,1425)","0","mstr_discrete","I296";
;
CDS_SEC"1"
ROOM"SB_PU_PD"
SEC_TYPE"0402"
SEC"1"
CDS_LOCATION"R7C8"
CDS_LIB"mstr_discrete"
LOCATION"R7C8"
VALUE"10.0K"
PART_NUMBER"G21796-016"
WATTAGE"1/16W"
TOLERANCE"1%"
MATERIAL"CHIP"
PACK_TYPE"0402";
"A"
$PN"1"6;
"B"
$PN"2"13;
%"RES"
"2","(-650,1425)","0","mstr_discrete","I297";
;
CDS_SEC"1"
CDS_LOCATION"R7C5"
SEC"1"
SEC_TYPE"0402"
ROOM"SB_PU_PD"
CDS_LIB"mstr_discrete"
MATERIAL"CHIP"
PACK_TYPE"0402"
VALUE"10.0K"
PART_NUMBER"G21796-016"
LOCATION"R7C5"
WATTAGE"1/16W"
TOLERANCE"1%";
"A"
$PN"1"6;
"B"
$PN"2"14;
%"P3V3_STBY"
"1","(-650,1850)","0","mstr_symbols","I298";
;
BODY_TYPE"PLUMBING"
CDS_LIB"mstr_symbols"
SIZE"1B"
VOLTAGE"3.3V"
HDL_POWER"P3V3_STBY";
"G\NAC"6;
%"P3V3_STBY"
"1","(-2800,2050)","0","mstr_symbols","I300";
;
CDS_LIB"mstr_symbols"
SIZE"1B"
BODY_TYPE"PLUMBING"
VOLTAGE"3.3V"
HDL_POWER"P3V3_STBY";
"G\NAC"7;
%"RES"
"1","(-2475,1800)","0","mstr_discrete","I301";
;
CDS_SEC"1"
CDS_LOCATION"R8D14"
SEC"1"
SEC_TYPE"0402"
ROOM"SB"
CDS_LIB"mstr_discrete"
BOM_COST"SB"
PACK_TYPE"0402"
PART_NUMBER"G21796-072"
LOCATION"R8D14"
MATERIAL"CHIP"
TOLERANCE"1%"
VALUE"4.75K"
WATTAGE"1/16W";
"B"
$PN"2"33;
"A"
$PN"1"7;
%"P3V3_STBY"
"1","(-4950,5225)","0","mstr_symbols","I302";
;
VOLTAGE"3.3V"
SIZE"1B"
CDS_LIB"mstr_symbols"
BODY_TYPE"PLUMBING"
HDL_POWER"P3V3_STBY";
"G\NAC"8;
%"RES"
"1","(-4675,2400)","0","mstr_discrete","I303";
;
CDS_SEC"1"
SEC_TYPE"0402"
SEC"1"
ROOM"SB_PU_PD"
CDS_LIB"mstr_discrete"
CDS_LOCATION"R8C6"
MATERIAL"CHIP"
TOLERANCE"1%"
PART_NUMBER"G21796-072"
VALUE"4.75K"
LOCATION"R8C6"
PACK_TYPE"0402"
WATTAGE"1/16W";
"B"
$PN"2"53;
"A"
$PN"1"2;
%"RES"
"1","(-4800,1825)","0","mstr_discrete","I304";
;
CDS_SEC"1"
SEC"1"
SEC_TYPE"0402"
ROOM"SB_PU_PD"
CDS_LIB"mstr_discrete"
CDS_LOCATION"R8C2"
MATERIAL"CHIP"
PACK_TYPE"0402"
TOLERANCE"1%"
PART_NUMBER"G21796-072"
LOCATION"R8C2"
VALUE"4.75K"
WATTAGE"1/16W";
"B"
$PN"2"47;
"A"
$PN"1"3;
%"RES"
"1","(-4700,3700)","0","mstr_discrete","I306";
;
CDS_SEC"1"
SEC_TYPE"0402"
SEC"1"
ROOM"SB_PU_PD"
CDS_LIB"mstr_discrete"
CDS_LOCATION"R7D6"
MATERIAL"CHIP"
TOLERANCE"1%"
VALUE"4.75K"
PART_NUMBER"G21796-072"
LOCATION"R7D6"
PACK_TYPE"0402"
WATTAGE"1/16W";
"B"
$PN"2"50;
"A"
$PN"1"8;
%"RES"
"1","(-4800,1650)","0","mstr_discrete","I307";
;
CDS_SEC"1"
SEC_TYPE"0402"
SEC"1"
ROOM"SB_PU_PD"
CDS_LIB"mstr_discrete"
CDS_LOCATION"R8B31"
MATERIAL"CHIP"
PACK_TYPE"0402"
TOLERANCE"1%"
PART_NUMBER"G21796-072"
LOCATION"R8B31"
WATTAGE"1/16W"
VALUE"4.75K";
"B"
$PN"2"46;
"A"
$PN"1"3;
%"RES"
"1","(-2475,1025)","0","mstr_discrete","I309";
;
CDS_SEC"1"
ROOM"SB_PU_PD"
SEC_TYPE"0402"
CDS_LIB"mstr_discrete"
SEC"1"
CDS_LOCATION"R2N7"
VALUE"4.75K"
LOCATION"R2N7"
PACK_TYPE"0402"
MATERIAL"CHIP"
PART_NUMBER"G21796-072"
TOLERANCE"1%"
WATTAGE"1/16W";
"B"
$PN"2"34;
"A"
$PN"1"5;
%"RES"
"1","(-400,5100)","0","mstr_discrete","I315";
;
CDS_SEC"1"
SEC_TYPE"0402"
SEC"1"
CDS_LOCATION"R3P7"
CDS_LIB"mstr_discrete"
ROOM"SB"
BOM_COST"SB"
WATTAGE"1/16W"
PART_NUMBER"G21796-026"
LOCATION"R3P7"
MATERIAL"CHIP"
PACK_TYPE"0402"
TOLERANCE"1%"
VALUE"1.00K";
"B"
$PN"2"16;
"A"
$PN"1"10;
%"RES"
"1","(-400,4875)","0","mstr_discrete","I316";
;
CDS_SEC"1"
SEC_TYPE"0402"
SEC"1"
CDS_LIB"mstr_discrete"
CDS_LOCATION"R3P5"
ROOM"SB"
BOM_COST"SB"
WATTAGE"1/16W"
MATERIAL"CHIP"
PACK_TYPE"0402"
PART_NUMBER"G21796-026"
LOCATION"R3P5"
TOLERANCE"1%"
VALUE"1.00K";
"B"
$PN"2"17;
"A"
$PN"1"10;
%"RES"
"1","(-375,4650)","0","mstr_discrete","I317";
;
CDS_SEC"1"
SEC"1"
SEC_TYPE"0402"
ROOM"SB"
CDS_LIB"mstr_discrete"
CDS_LOCATION"R3P6"
BOM_COST"SB"
PART_NUMBER"G21796-026"
WATTAGE"1/16W"
MATERIAL"CHIP"
PACK_TYPE"0402"
LOCATION"R3P6"
TOLERANCE"1%"
VALUE"1.00K";
"B"
$PN"2"18;
"A"
$PN"1"10;
%"RES"
"1","(-375,4400)","0","mstr_discrete","I318";
;
CDS_SEC"1"
SEC"1"
SEC_TYPE"0402"
ROOM"SB"
CDS_LIB"mstr_discrete"
CDS_LOCATION"R3N15"
BOM_COST"SB"
PART_NUMBER"G21796-026"
WATTAGE"1/16W"
MATERIAL"CHIP"
PACK_TYPE"0402"
LOCATION"R3N15"
TOLERANCE"1%"
VALUE"1.00K";
"B"
$PN"2"19;
"A"
$PN"1"10;
%"RES"
"1","(-375,4175)","0","mstr_discrete","I321";
;
CDS_SEC"1"
SEC_TYPE"0402"
SEC"1"
ROOM"SB"
CDS_LIB"mstr_discrete"
CDS_LOCATION"R3N16"
BOM_COST"SB"
PART_NUMBER"G21796-026"
WATTAGE"1/16W"
MATERIAL"CHIP"
PACK_TYPE"0402"
LOCATION"R3N16"
TOLERANCE"1%"
VALUE"1.00K";
"B"
$PN"2"20;
"A"
$PN"1"10;
%"RES"
"1","(-375,3925)","0","mstr_discrete","I322";
;
CDS_SEC"1"
SEC_TYPE"0402"
SEC"1"
ROOM"SB"
CDS_LIB"mstr_discrete"
CDS_LOCATION"R3P8"
BOM_COST"SB"
PART_NUMBER"G21796-026"
WATTAGE"1/16W"
MATERIAL"CHIP"
PACK_TYPE"0402"
TOLERANCE"1%"
LOCATION"R3P8"
VALUE"1.00K";
"B"
$PN"2"21;
"A"
$PN"1"10;
%"RES"
"1","(-4800,1300)","0","mstr_discrete","I326";
;
CDS_SEC"1"
SEC_TYPE"0402"
SEC"1"
ROOM"SB_PU_PD"
CDS_LIB"mstr_discrete"
CDS_LOCATION"R8C1"
MATERIAL"CHIP"
PACK_TYPE"0402"
TOLERANCE"1%"
PART_NUMBER"G21796-072"
LOCATION"R8C1"
VALUE"4.75K"
WATTAGE"1/16W";
"B"
$PN"2"42;
"A"
$PN"1"3;
%"RES"
"1","(-4800,1125)","0","mstr_discrete","I327";
;
CDS_SEC"1"
SEC"1"
SEC_TYPE"0402"
ROOM"SB_PU_PD"
CDS_LIB"mstr_discrete"
CDS_LOCATION"R8C7"
BOM_COST"SB"
MATERIAL"CHIP"
PACK_TYPE"0402"
TOLERANCE"1%"
PART_NUMBER"G21796-072"
LOCATION"R8C7"
WATTAGE"1/16W"
VALUE"4.75K";
"B"
$PN"2"44;
"A"
$PN"1"3;
%"RES"
"1","(-4700,4700)","0","mstr_discrete","I331";
;
CDS_SEC"1"
SEC"1"
SEC_TYPE"0402"
ROOM"SB"
CDS_LIB"mstr_discrete"
CDS_LOCATION"R7D7"
BOM_COST"SB_PU_PD"
TOLERANCE"1%"
PACK_TYPE"0402"
MATERIAL"CHIP"
PART_NUMBER"G21796-026"
LOCATION"R7D7"
VALUE"1.00K"
WATTAGE"1/16W";
"B"
$PN"2"49;
"A"
$PN"1"8;
%"RES"
"1","(-4700,5100)","0","mstr_discrete","I332";
;
CDS_SEC"1"
SEC_TYPE"0402"
SEC"1"
CDS_LOCATION"R7D2"
CDS_LIB"mstr_discrete"
ROOM"SB"
BOM_COST"SB_PU_PD"
LOCATION"R7D2"
PACK_TYPE"0402"
VALUE"1.00K"
TOLERANCE"1%"
MATERIAL"CHIP"
PART_NUMBER"G21796-026"
WATTAGE"1/16W";
"B"
$PN"2"48;
"A"
$PN"1"8;
%"RES"
"1","(-2500,3150)","0","mstr_discrete","I333";
;
CDS_SEC"1"
SEC"1"
SEC_TYPE"0402"
CDS_LIB"mstr_discrete"
ROOM"SB_PU_PD"
CDS_LOCATION"R8C25"
MATERIAL"CHIP"
PACK_TYPE"0402"
TOLERANCE"1%"
LOCATION"R8C25"
PART_NUMBER"G21796-072"
VALUE"4.75K"
WATTAGE"1/16W";
"B"
$PN"2"30;
"A"
$PN"1"9;
%"P3V3_STBY"
"1","(-2775,3425)","0","mstr_symbols","I335";
;
SIZE"1B"
CDS_LIB"mstr_symbols"
BODY_TYPE"PLUMBING"
VOLTAGE"3.3V"
HDL_POWER"P3V3_STBY";
"G\NAC"9;
%"P1V05_PCH_STBY"
"1","(-625,5325)","0","mstr_symbols","I339";
;
VOLTAGE"1.05V"
HDL_POWER"P1V05_PCH_STBY"
CDS_LIB"mstr_symbols"
BODY_TYPE"PLUMBING";
"G\NAC"10;
%"RES"
"1","(-2475,2700)","0","mstr_discrete","I341";
;
CDS_SEC"1"
CDS_LOCATION"R2N32"
SEC_TYPE"0402"
SEC"1"
ROOM"SB"
CDS_LIB"mstr_discrete"
BOM_COST"SB"
PART_NUMBER"G21796-072"
TOLERANCE"1%"
LOCATION"R2N32"
MATERIAL"CHIP"
PACK_TYPE"0402"
VALUE"4.75K"
WATTAGE"1/16W";
"B"
$PN"2"31;
"A"
$PN"1"11;
%"P3V3_STBY"
"1","(-2800,2875)","0","mstr_symbols","I342";
;
SIZE"1B"
CDS_LIB"mstr_symbols"
VOLTAGE"3.3V"
BODY_TYPE"PLUMBING"
HDL_POWER"P3V3_STBY";
"G\NAC"11;
%"RES"
"1","(-375,2725)","0","mstr_discrete","I349";
;
CDS_SEC"1"
CDS_LOCATION"R2M8"
SEC_TYPE"0402"
SEC"1"
ROOM"SB"
CDS_LIB"mstr_discrete"
BOM_COST"SB"
PACK_TYPE"0402"
WATTAGE"1/16W"
MATERIAL"CHIP"
PART_NUMBER"G21796-003"
LOCATION"R2M8"
TOLERANCE"1%"
VALUE"1.5K";
"B"
$PN"2"22;
"A"
$PN"1"12;
%"RES"
"1","(-375,2475)","0","mstr_discrete","I352";
;
CDS_SEC"1"
CDS_LOCATION"R2N29"
SEC_TYPE"0402"
SEC"1"
ROOM"SB"
CDS_LIB"mstr_discrete"
BOM_COST"SB"
PACK_TYPE"0402"
WATTAGE"1/16W"
MATERIAL"CHIP"
PART_NUMBER"G21796-003"
LOCATION"R2N29"
TOLERANCE"1%"
VALUE"1.5K";
"B"
$PN"2"23;
"A"
$PN"1"12;
%"P3V3_STBY"
"1","(-625,2950)","0","mstr_symbols","I353";
;
VOLTAGE"3.3V"
SIZE"1B"
CDS_LIB"mstr_symbols"
BODY_TYPE"PLUMBING"
HDL_POWER"P3V3_STBY";
"G\NAC"12;
%"RES"
"1","(-4700,3475)","0","mstr_discrete","I355";
;
CDS_SEC"1"
ROOM"SB"
SEC_TYPE"0402"
SEC"1"
CDS_LIB"mstr_discrete"
CDS_LOCATION"R8E3"
PART_NUMBER"G21796-016"
MATERIAL"CHIP"
PACK_TYPE"0402"
WATTAGE"1/16W"
TOLERANCE"1%"
LOCATION"R8E3"
VALUE"10.0K";
"B"
$PN"2"38;
"A"
$PN"1"8;
%"RES"
"1","(-375,3725)","0","mstr_discrete","I356";
;
CDS_SEC"1"
CDS_LOCATION"R7D44"
SEC_TYPE"0402"
SEC"1"
ROOM"SB_PU_PD"
CDS_LIB"mstr_discrete"
MATERIAL"CHIP"
PACK_TYPE"0402"
TOLERANCE"1%"
PART_NUMBER"G21796-072"
LOCATION"R7D44"
WATTAGE"1/16W"
VALUE"4.75K";
"B"
$PN"2"24;
"A"
$PN"1"10;
%"RES"
"1","(-375,3525)","0","mstr_discrete","I357";
;
CDS_SEC"1"
CDS_LOCATION"R3P53"
ROOM"SB_PU_PD"
SEC_TYPE"0402"
SEC"1"
CDS_LIB"mstr_discrete"
LOCATION"R3P53"
MATERIAL"CHIP"
PACK_TYPE"0402"
TOLERANCE"1%"
PART_NUMBER"G21796-072"
VALUE"4.75K"
WATTAGE"1/16W";
"B"
$PN"2"25;
"A"
$PN"1"10;
%"RES"
"1","(-4800,1500)","0","mstr_discrete","I360";
;
CDS_SEC"1"
CDS_LOCATION"R2P22"
SEC_TYPE"0402"
SEC"1"
CDS_LIB"mstr_discrete"
ROOM"SB"
BOM_COST"SB"
PACK_TYPE"0402"
PART_NUMBER"G21796-016"
LOCATION"R2P22"
TOLERANCE"1%"
MATERIAL"CHIP"
VALUE"10.0K"
WATTAGE"1/16W";
"B"
$PN"2"45;
"A"
$PN"1"3;
%"RES"
"1","(-2475,2450)","0","mstr_discrete","I362";
;
CDS_SEC"1"
CDS_LOCATION"R8D44"
SEC_TYPE"0402"
SEC"1"
ROOM"SB"
CDS_LIB"mstr_discrete"
BOM_COST"SB"
PART_NUMBER"G21796-016"
PACK_TYPE"0402"
MATERIAL"CHIP"
TOLERANCE"1%"
LOCATION"R8D44"
VALUE"10.0K"
WATTAGE"1/16W";
"B"
$PN"2"32;
"A"
$PN"1"11;
END.
